# BASEBOARD_FAB2 (Tioga Pass) — schematic parts with pin connectivity, parts 3454–3616 of 4751; source: Cadence DE-HDL packaged netlist (pstxprt.dat, pstxnet.dat, pstchip.dat)

R6L5  RES  1.0M 1% EMPTY  pkg 0402  page 230 : 1 = P3V3 ; 2 = FM_PVTT_KLM_EN_R
R6L6  RES  0.0 5% CHIP  pkg 0402  page 230 : 1 = PVDDQ_KLM ; 2 = VSENSE_PVDDQ_KLM_VTT
R6L8  RES  0.0 5% CHIP  pkg 0402  page 230 : 1 = P3V3 ; 2 = VR_PVTT_KLM_BIAS
R6L9  RES  10.0K 1% CHIP  pkg 0402  page 222 : 1 = P3V3 ; 2 = PWRGD_PVTT_DEF_CPU0_R
R6L10  RES  0.0 5% CHIP  pkg 0402  page 222 : 1 = PVDDQ_DEF ; 2 = VSENSE_PVDDQ_DEF_VTT
R6L11  RES  0.0 5% CHIP  pkg 0402  page 222 : 1 = P3V3 ; 2 = VR_PVTT_DEF_BIAS
R6L12  RES  1.00K 1% CHIP  pkg 0402  page 98 : 1 = M_E_VREF ; 2 = GND
R6L13  RES  1.00K 1% CHIP  pkg 0402  page 98 : 1 = PVDDQ_DEF ; 2 = M_E_VREF
R6L14  RES  2 1.0% CHIP  pkg 0402  page 98 : 1 = M_E_CPU_VREF ; 2 = M_E_VREF
R6L16  RES  1.00K 1% CHIP  pkg 0402  page 98 : 1 = M_D_VREF ; 2 = GND
R6M1  RES  1.00K 1% CHIP  pkg 0402  page 98 : 1 = PVDDQ_DEF ; 2 = M_D_VREF
R6M2  RES  2 1.0% CHIP  pkg 0402  page 98 : 1 = M_D_CPU_VREF ; 2 = M_D_VREF
R6M4  RES  4.75K 1% CHIP  pkg 0402  page 94 : 1 = P3V3 ; 2 = H_CPU1_MEMKLM_MEMHOT
R6M8  RES  1.00K 1% CHIP  pkg 0402  page 113 : 1 = JTAG_MCP_CPU1_TDI_R ; 2 = JTAG_MCP_CPU1_TDI
R6M9  RES  4.75K 1% CHIP  pkg 0402  page 192 : 1 = PVPP_KLM ; 2 = RST_CD_CPU1_POR_N
R6N1  RES  49.9 1% CHIP  pkg 0402  page 21 : 1 = SVID_ALERT0_CPU0_R_N ; 2 = PVCCIO_CPU0
R6N2  RES  100.0 1% CHIP  pkg 0402  page 21 : 1 = SVID_DIO0_CPU0_R ; 2 = PVCCIO_CPU0
R6N3  RES  0.0 5% CHIP  pkg 0402  page 205 : 1 = VR_PVSA_CPU0_VCIN ; 2 = P5V_STBY
R6N4  RES  51.1 1.0% CHIP  pkg 0402  page 205 : 1 = PVSA_CPU0 ; 2 = GND
R6N8  RES  10.0 1% CHIP  pkg 0402  page 163 : 1 = SMB_CPU1_PE_HP_GTL_SCL ; 2 = SMB_CPU1_PE_HP_GTL_R_SCL
R6N9  RES  10.0 1% CHIP  pkg 0402  page 163 : 1 = SMB_CPU1_PE_HP_GTL_SDA ; 2 = SMB_CPU1_PE_HP_GTL_R_SDA
R6N10  RES  221 1.0% CHIP  pkg 0402  page 21 : 1 = SVID_ALERT0_CPU0_N ; 2 = SVID_ALERT0_CPU0_R_N
R6N11  RES  0.0 5% CHIP  pkg 0402  page 21 : 1 = SVID_DIO0_CPU0 ; 2 = SVID_DIO0_CPU0_R
R6N12  RES  0.0 5% CHIP  pkg 0402  page 21 : 1 = SVID_CLK0_CPU0 ; 2 = SVID_CLK0_CPU0_R
R6N13  RES  1.00K 1% CHIP  pkg 0402  page 156 : 1 = GND ; 2 = PD_PIROM_CPU0_ADDR1
R6N14  RES  1.00K 1% CHIP  pkg 0402  page 156 : 1 = GND ; 2 = PD_PIROM_CPU0_ADDR0
R6N15  RES  1.00K 1% CHIP  pkg 0402  page 156 : 1 = GND ; 2 = PD_PIROM_CPU0_ADDR2
R6P1  RES  42.2 1.0% EMPTY  pkg 0402  page 103 : 1 = CLK_100M_CPU0_RC_REFCLK0_DP ; 2 = GND
R6P2  RES  42.2 1.0% EMPTY  pkg 0402  page 103 : 1 = CLK_100M_CPU0_RC_REFCLK0_DN ; 2 = GND
R6P3  RES  42.2 1.0% EMPTY  pkg 0402  page 103 : 1 = CLK_100M_CPU0_RC_REFCLK1_DP ; 2 = GND
R6P4  RES  42.2 1.0% EMPTY  pkg 0402  page 103 : 1 = CLK_100M_CPU0_RC_REFCLK1_DN ; 2 = GND
R6P5  RES  42.2 1.0% EMPTY  pkg 0402  page 103 : 1 = CLK_100M_CPU1_BCLK0_DP ; 2 = GND
R6P6  RES  42.2 1.0% EMPTY  pkg 0402  page 103 : 1 = CLK_100M_CPU1_BCLK0_DN ; 2 = GND
R6P7  RES  42.2 1.0% EMPTY  pkg 0402  page 103 : 1 = CLK_100M_CPU1_BCLK1_DP ; 2 = GND
R6P8  RES  42.2 1.0% EMPTY  pkg 0402  page 103 : 1 = CLK_100M_CPU1_BCLK1_DN ; 2 = GND
R6P9  RES  42.2 1.0% EMPTY  pkg 0402  page 103 : 1 = CLK_100M_CPU0_PE_REFCLK_DN ; 2 = GND
R6P10  RES  0.0 5% CHIP  pkg 0402  page 203 : 1 = VR_PVCCIN_CPU0_PH4_VCIN ; 2 = P5V_STBY
R6P11  RES  42.2 1.0% EMPTY  pkg 0402  page 103 : 1 = CLK_100M_CPU0_PE_REFCLK_DP ; 2 = GND
R6P12  RES  42.2 1.0% EMPTY  pkg 0402  page 103 : 1 = CLK_100M_CPU0_BCLK2_DN ; 2 = GND
R6P13  RES  42.2 1.0% EMPTY  pkg 0402  page 103 : 1 = CLK_100M_CPU0_BCLK2_DP ; 2 = GND
R6P15  RES  42.2 1.0% EMPTY  pkg 0402  page 103 : 1 = CLK_100M_CPU0_BCLK0_DN ; 2 = GND
R6P16  RES  1.00K 1% CHIP  pkg 0402  page 201 : 1 = PVCCIO_CPU0 ; 2 = VR_PVCCIN_CPU0_VREN
R6P17  RES  42.2 1.0% EMPTY  pkg 0402  page 103 : 1 = CLK_100M_CPU0_BCLK0_DP ; 2 = GND
R6P18  RES  0.0 5% CHIP  pkg 0402  page 201 : 1 = FM_PVCCIN_PVCCSA_CPU0_EN_LVC1 ; 2 = VR_PVCCIN_CPU0_VREN
R6P19  RES  0.0 5% CHIP  pkg 0402  page 203 : 1 = VR_PVCCIN_CPU0_PH3_VCIN ; 2 = P5V_STBY
R6P20  RES  1.00K 1% CHIP  pkg 0402  page 102 : 1 = FM_DB1200_SMB_SA1 ; 2 = GND
R6P21  RES  1.00K 1% CHIP  pkg 0402  page 102 : 1 = FM_DB1200_SMB_SA0 ; 2 = GND
R6P22  RES  4.75K 1% EMPTY  pkg 0402  page 102 : 1 = FM_HBW_BYPASS_LOWBW_N ; 2 = GND
R6P23  RES  4.75K 1% EMPTY  pkg 0402  page 102 : 1 = FM_100M_N ; 2 = GND
R6P25  RES  2.2 1.0% CHIP  pkg 0603  page 102 : 1 = P3V3_DB1200 ; 2 = P3V3_DB1200_R
R6P27  RES  4.02K 1% CHIP  pkg 0402  page 201 : 1 = VR_PVCCIN_CPU0_XADDR2 ; 2 = GND
R6P28  RES  4.02K 1% CHIP  pkg 0402  page 201 : 1 = VR_PVCCIN_CPU0_XADDR1 ; 2 = GND
R6P32  RES  2.0K 1% EMPTY  pkg 0402  page 201 : 1 = P3V3_STBY ; 2 = SMB_VR_STBY_LVC3_SDA
R6P33  RES  110 1% EMPTY  pkg 0402  page 213 : 1 = PVCCIO_CPU1 ; 2 = SVID_CLK0_CPU1_R
R6P35  RES  100.0 1% EMPTY  pkg 0402  page 213 : 1 = PVCCIO_CPU1 ; 2 = SVID_DIO0_CPU1_R
R6P37  RES  2.0K 1% EMPTY  pkg 0402  page 201 : 1 = P3V3_STBY ; 2 = SMB_VR_STBY_LVC3_SCL
R6P39  RES  4.75K 1% CHIP  pkg 0402  page 55 : 1 = P3V3_STBY ; 2 = FM_CPU1_SKTOCC_LVT3_N
R6P40  RES  100.0K 1% EMPTY  pkg 0402  page 213 : 1 = P3V3_STBY ; 2 = VR_PVCCIO_CPU1_EN
R6P41  RES  0.0 5% CHIP  pkg 0402  page 213 : 1 = FM_PVCCIO_CPU1_EN ; 2 = VR_PVCCIO_CPU1_EN
R6P45  RES  33.2 1% CHIP  pkg 0402  page 201 : 1 = IRQ_PVCCIN_CPU0_VRHOT_LVC3_R_N ; 2 = IRQ_PVCCIN_CPU0_VRHOT_LVC3_N
R6P46  RES  100.0 1% CHIP  pkg 0402  page 112 : 1 = PVCCIO_CPU0 ; 2 = XDP_CPU_MBP1_N
R6P47  RES  0.0 5% CHIP  pkg 0402  page 204 : 1 = VR_PVCCIN_CPU0_PH5_VCIN ; 2 = P5V_STBY
R6P48  RES  1.00K 1% CHIP  pkg 0402  page 102 : 1 = P3V3 ; 2 = FM_DB1200ZL_BCLKS_EN_N
R6P49  RES  2.26K 1.0% EMPTY  pkg 0402  page 213 : 1 = P3V3_STBY ; 2 = PU_VR_PVCCIO_CPU1_FAULT1
R6R2  RES  0.0 5% CHIP  pkg 0402  page 202 : 1 = VR_PVCCIN_CPU0_PH1_VCIN ; 2 = P5V_STBY
R6R5  RES  0.0 5% CHIP  pkg 0402  page 214 : 1 = VR_PVCCIO_CPU1_PH1_VCIN ; 2 = P5V_STBY
R6R6  RES  0.0 5% CHIP  pkg 0402  page 202 : 1 = VR_PVCCIN_CPU0_PH2_VCIN ; 2 = P5V_STBY
R6T1  RES  240 1.0% CHIP  pkg 0402  page 99 : 1 = PVCCIO_CPU1 ; 2 = SMB_DDR_GHJ_SDA_G
R6T2  RES  240 1.0% CHIP  pkg 0402  page 99 : 1 = PVCCIO_CPU1 ; 2 = SMB_DDR_GHJ_SCL_G
R6T3  RES  10.0 1% CHIP  pkg 0402  page 99 : 1 = SMB_DDR_GHJ_SCL_G_R ; 2 = SMB_DDR_GHJ_SCL_G
R6T4  RES  10.0 1% CHIP  pkg 0402  page 99 : 1 = SMB_DDR_GHJ_SDA_G_R ; 2 = SMB_DDR_GHJ_SDA_G
R6T5  RES  1.00K 1% CHIP  pkg 0402  page 112 : 1 = XDP_CPU_TRST_N ; 2 = GND
R6T6  RES  150.0 1% CHIP  pkg 0402  page 112 : 1 = PVCCIO_CPU1 ; 2 = XDP_CPU1_TDI
R6T7  RES  150.0 1% CHIP  pkg 0402  page 112 : 1 = PVCCIO_CPU1 ; 2 = XDP_CPU1_TDO
R6T8  RES  100.0 1% CHIP  pkg 0402  page 112 : 1 = PVCCIO_CPU0 ; 2 = XDP_CPU_OBSFN_B0_MBP6_N
R6T9  RES  100.0 1% CHIP  pkg 0402  page 112 : 1 = PVCCIO_CPU0 ; 2 = XDP_CPU_OBSFN_B1_MBP7_N
R6U3  RES  1.0M 1% EMPTY  pkg 0402  page 229 : 1 = P3V3 ; 2 = FM_PVTT_GHJ_EN_R
R6U4  RES  0.0 5% CHIP  pkg 0402  page 221 : 1 = P3V3 ; 2 = VR_PVTT_ABC_BIAS
R6U5  RES  0.0 5% CHIP  pkg 0402  page 221 : 1 = PVDDQ_ABC ; 2 = VSENSE_PVDDQ_ABC_VTT
R6U6  RES  0.0 5% CHIP  pkg 0402  page 229 : 1 = PVDDQ_GHJ ; 2 = VSENSE_PVDDQ_GHJ_VTT
R6U7  RES  0.0 5% CHIP  pkg 0402  page 229 : 1 = P3V3 ; 2 = VR_PVTT_GHJ_BIAS
R6U13  RES  20.0 1% CHIP  pkg 0402  page 99 : 1 = SMB_DDR_GHJ_VPP_SCL_R ; 2 = SMB_DDR_GHJ_VPP_SCL
R6U14  RES  20.0 1% CHIP  pkg 0402  page 99 : 1 = SMB_DDR_GHJ_VPP_SDA_R ; 2 = SMB_DDR_GHJ_VPP_SDA
R6U15  RES  1.0M 1% EMPTY  pkg 0402  page 221 : 1 = P3V3 ; 2 = FM_PVTT_ABC_EN_R
R6U17  RES  665 1.0% CHIP  pkg 0402  page 99 : 1 = PVPP_GHJ ; 2 = SMB_DDR_GHJ_VPP_SCL_R
R6U18  RES  665 1.0% CHIP  pkg 0402  page 99 : 1 = PVPP_GHJ ; 2 = SMB_DDR_GHJ_VPP_SDA_R
R6W1  RES  4.75K 1% CHIP  pkg 0402  page 137 : 1 = P3V3_STBY ; 2 = PU_UV_HIGH_SET
R6W2  RES  10.0K 1% CHIP  pkg 0402  page 137 : 1 = PD_UV_HIGH_SET ; 2 = GND
R6W3  232KR2F-2-GP  1%  pkg SMD-RG1  page 200 : 1 = UV_HIGH_SET_N ; 2 = A_P12V_STBY_FP_TRIGGER
R6W4  RES  4.75K 1% CHIP  pkg 0402  page 247 : 1 = P3V3_STBY ; 2 = PCA9555_A2
R6W5  RES  4.75K 1% CHIP  pkg 0402  page 247 : 1 = P3V3_STBY ; 2 = PCA9555_A1
R6W6  RES  4.75K 1% CHIP  pkg 0402  page 247 : 1 = P3V3_STBY ; 2 = PCA9555_A0
R6W7  RES  4.75K 1% EMPTY  pkg 0402  page 247 : 1 = PCA9555_A2 ; 2 = GND
R6W8  RES  4.75K 1% EMPTY  pkg 0402  page 247 : 1 = PCA9555_A1 ; 2 = GND
R6W9  RES  4.75K 1% EMPTY  pkg 0402  page 247 : 1 = PCA9555_A0 ; 2 = GND
R6W10  RES  4.75K 1% CHIP  pkg 0402  page 247 : 1 = P3V3_STBY ; 2 = PCA9555_INT_N
R6W11  RES  4.75K 1% CHIP  pkg 0402  page 247 : 1 = SMB_DEBUG_STBY_LVC3_SCL ; 2 = P3V3_STBY
R6W12  RES  4.75K 1% CHIP  pkg 0402  page 247 : 1 = SMB_DEBUG_STBY_LVC3_SDA ; 2 = P3V3_STBY
R6W16  RES  1.00K 1% CHIP  pkg 0402  page 168 : 1 = P3V3_STBY ; 2 = FM_SOL_UART_CH_SEL
R6W17  RES  0.0 5% CHIP  pkg 0402  page 145 : 1 = SMB_DEBUG_STBY_LVC3_SCL ; 2 = SMB_DEBUG_STBY_LVC3_SCL_R
R6W18  RES  0.0 5% CHIP  pkg 0402  page 145 : 1 = SMB_DEBUG_STBY_LVC3_SDA ; 2 = SMB_DEBUG_STBY_LVC3_SDA_R
R6W19  RES  0.0 5% CHIP  pkg 0402  page 155 : 1 = SPA_5V_SIN_SW_D ; 2 = SPA_SIN_SW_R
R6W20  RES  20.0 1% CHIP  pkg 0402  page 247 : 1 = SMB_HOST_STBY_LVC3_SDA_R3 ; 2 = SMB_HOST_STBY_LVC3_SDA
R6W21  RES  1.00K 1% CHIP  pkg 0402  page 247 : 1 = P3V3_STBY ; 2 = PU_ID_EEPROM_A0
R6W22  RES  20.0 1% CHIP  pkg 0402  page 247 : 1 = SMB_HOST_STBY_LVC3_SCL ; 2 = SMB_HOST_STBY_LVC3_SCL_R3
R6W23  RES  1.00K 1% CHIP  pkg 0402  page 247 : 1 = PD_ID_EEPROM_WP ; 2 = GND
R6W24  RES  4.75K 1% CHIP  pkg 0402  page 247 : 1 = P3V3_STBY ; 2 = SMB_PMBUS_BMC_STBY_LVC3_SDA_R1
R6W25  RES  4.75K 1% CHIP  pkg 0402  page 247 : 1 = P3V3_STBY ; 2 = SMB_PMBUS_BMC_STBY_LVC3_SCL_R1
R6W26  RES  10.0 1% CHIP  pkg 0402  page 248 : 1 = SMB_CPU0_PE_HP_GTL_SCL ; 2 = SMB_CPU0_PE_HP_GTL_R_SCL
R6W27  RES  10.0 1% CHIP  pkg 0402  page 248 : 1 = SMB_CPU0_PE_HP_GTL_SDA ; 2 = SMB_CPU0_PE_HP_GTL_R_SDA
R6W28  RES  4.75K 1% CHIP  pkg 0402  page 247 : 1 = P3V3_STBY ; 2 = HSC_SMBUS_SWITCH_EN
R6W29  RES  10.0K 1% CHIP  pkg 0402  page 89 : 1 = PVPP_ABC ; 2 = FM_ADR_COMPLETE_CPU1_N
R6W30  RES  100.0K 1% CHIP  pkg 0603  page 176 : 1 = P3V3_STBY ; 2 = SPA_MID_DBG2_RX_BUF
R6W35  RES  100.0K 1% CHIP  pkg 0402  page 247 : 1 = P3V3_STBY ; 2 = FM_CPU_CATERR_MSMI_LVT3_N
R6W36  RES  10.0 1% CHIP  pkg 0402  page 176 : 1 = SPA_MID_DBG1_TX_R ; 2 = SPA_MID_DBG1_TX
R6W37  RES  10.0 1% CHIP  pkg 0402  page 176 : 1 = SPA_MID_DBG2_TX_R ; 2 = SPA_MID_DBG2_TX
R6W38  RES  20.0K 1% CHIP  pkg 0402  page 176 : 1 = DEBUG_CARD2_PRSNT ; 2 = GND
R6W39  RES  10.0K 1% CHIP  pkg 0402  page 176 : 1 = SPA_MID_DBG1_TX_EN ; 2 = P3V3_STBY
R6W40  RES  10.0K 1% CHIP  pkg 0402  page 155 : 1 = P3V3_STBY ; 2 = SPA_5V_SIN_SW_D
R6W41  RES  4.75K 1% CHIP  pkg 0402  page 164 : 1 = P3V3_STBY ; 2 = PCA9554_INT_N
R6W42  RES  4.75K 1% EMPTY  pkg 0402  page 164 : 1 = P3V3_STBY ; 2 = PCA9554_A2
R6W43  RES  4.75K 1% EMPTY  pkg 0402  page 164 : 1 = P3V3_STBY ; 2 = PCA9554_A1
R6W44  RES  4.75K 1% CHIP  pkg 0402  page 164 : 1 = P3V3_STBY ; 2 = PCA9554_A0
R6W45  RES  4.75K 1% CHIP  pkg 0402  page 164 : 1 = PCA9554_A2 ; 2 = GND
R6W46  RES  4.75K 1% CHIP  pkg 0402  page 164 : 1 = PCA9554_A1 ; 2 = GND
R6W47  RES  4.75K 1% EMPTY  pkg 0402  page 164 : 1 = PCA9554_A0 ; 2 = GND
R6W49  RES  40.2K 1% CHIP  pkg 0402  page 168 : 1 = FM_UART_SWITCH_N ; 2 = FM_UART_SEL_N
R6W50  RES  4.75K 1% CHIP  pkg 0402  page 176 : 1 = P3V3_STBY ; 2 = SPA_MID_DBG2_RX
R7A7  RES  10.0 1% CHIP  pkg 0402  page 218 : 1 = VSENSE_PVDDQ_DEF_P ; 2 = VR_PVDDQ_DEF_AVSP
R7A8  RES  2.26K 1.0% CHIP  pkg 0402  page 218 : 1 = VR_PVDDQ_DEF_XADDR2 ; 2 = GND
R7A9  RES  2.26K 1.0% CHIP  pkg 0402  page 218 : 1 = P3V3_STBY ; 2 = PWRGD_PVDDQ_DEF
R7A10  RES  16K 1.0% CHIP  pkg 0402  page 218 : 1 = VR_PVDDQ_DEF_XADDR1 ; 2 = GND
R7A11  RES  0.0 5% CHIP  pkg 0402  page 218 : 1 = SVID_ALERT_PVDDQ_DEF ; 2 = SVID_ALERT1_CPU0_R_N
R7A12  RES  0.0 5% CHIP  pkg 0402  page 218 : 1 = SVID_VDIO_PVDDQ_DEF ; 2 = SVID_DIO1_CPU0_R
R7A13  RES  100.0 1% CHIP  pkg 0402  page 236 : 1 = VSENSE_PVNN_PCH_STBY_AVSP ; 2 = PVNN_PCH_STBY
R7A14  RES  10.0 1% CHIP  pkg 0402  page 236 : 1 = VSENSE_PVNN_PCH_STBY_FPK ; 2 = VSENSE_PVNN_PCH_STBY_AVSP
R7A15  RES  2.2 5% EMPTY  pkg 0402  page 232 : 1 = VR_PVPP_DEF_SNUB ; 2 = GND
R7A17  RES  150.0 1% CHIP  pkg 0402  page 218 : 1 = SVID_CLK1_CPU0_R ; 2 = SVID_CLK_PVDDQ_DEF
R7A18  RES  0.0 5% CHIP  pkg 0402  page 236 : 1 = GND ; 2 = VSENSE_PVNN_PCH_STBY_AVSN
R7A19  RES  10.0 1% CHIP  pkg 0402  page 236 : 1 = VSENSE_PVNN_PCH_STBY_QAT ; 2 = VSENSE_PVNN_PCH_STBY_AVSP
R7A20  RES  68.1K 1% EMPTY  pkg 0402  page 219 : 1 = VR_PVDDQ_DEF_PH1_OCSET ; 2 = GND
R7A21  RES  68.1K 1% EMPTY  pkg 0402  page 219 : 1 = VR_PVDDQ_DEF_PH2_OCSET ; 2 = GND
R7B1  RES  33.2 1% CHIP  pkg 0402  page 218 : 1 = IRQ_PVDDQ_DEF_VRHOT_LVT3_R_N ; 2 = IRQ_PVDDQ_DEF_VRHOT_LVT3_N
R7B4  RES  1.00K 1% CHIP  pkg 0402  page 218 : 1 = P3V3_STBY ; 2 = IRQ_PVDDQ_DEF_VRHOT_LVT3_R_N
R7B5  RES  1.00K 1% CHIP  pkg 0402  page 218 : 1 = P3V3_STBY ; 2 = PWRGD_PVDDQ_DEF_R
R7B6  RES  10.0K 1% CHIP  pkg 0402  page 133 : 1 = P3V3_STBY ; 2 = FM_PCH_PRSNT_N
R7B7  RES  10.0K 1% EMPTY  pkg 0402  page 116 : 1 = A_EXTCLKP ; 2 = GND
R7B8  RES  10.0K 1% EMPTY  pkg 0402  page 116 : 1 = A_EXTCLKN ; 2 = GND
R7B9  RES  0.0 5% CHIP  pkg 0402  page 232 : 1 = FM_PVPP_CPU0_EN ; 2 = FM_PVPP_PVDDQ_CPU0_EN_DEF
R7B10  RES  120.0 1% CHIP  pkg 0603  page 232 : 1 = PVPP_DEF ; 2 = GND
R7B11  RES  0.0 5% CHIP  pkg 0402  page 232 : 1 = PVPP_DEF ; 2 = VSENSE_PVPP_DEF
R7B12  RES  22.1 1.0% CHIP  pkg 0402  page 232 : 1 = PWRGD_PVPP_DEF_R ; 2 = PWRGD_PVPP_DEF
R7B13  RES  6.19K 1% CHIP  pkg 0402  page 232 : 1 = VR_FB_PVPP_DEF ; 2 = AGND_PVPP_DEF
R7B14  RES  7.87K 1.0% CHIP  pkg 0402  page 232 : 1 = VR_PVPP_DEF_ISET ; 2 = AGND_PVPP_DEF
R7B15  RES  20.0K 1% CHIP  pkg 0402  page 232 : 1 = VSENSE_PVPP_DEF ; 2 = VR_FB_PVPP_DEF
R7B16  RES  7.87K 1.0% CHIP  pkg 0402  page 232 : 1 = VR_COMP_RC_PVPP_DEF ; 2 = VR_FB_PVPP_DEF
R7B17  RES  1.00K 1% CHIP  pkg 0402  page 232 : 1 = P3V3_STBY ; 2 = PWRGD_PVPP_DEF_R
R7B18  RES  1.0K 0.1% CHIP  pkg 0402  page 232 : 1 = VSENSE_PVPP_DEF ; 2 = VR_COMP_PVPP_DEF
R7B19  RES  0 5.0% CHIP  pkg 0603  page 232 : 1 = VR_PVPP_DEF_BOOT ; 2 = VR_PVPP_DEF_BOOT_R
R7B20  RES  0.0 5% CHIP  pkg 0402  page 232 : 1 = GND ; 2 = AGND_PVPP_DEF
R7C1  RES  200K 0.1% CHIP  pkg 0603  page 114 : 1 = XTAL_PCH_48M_IN ; 2 = XTAL_PCH_48M_OUT
R7C2  RES  0.0 5% CHIP  pkg 0402  page 114 : 1 = CLK_100M_BMC_PE_R_DN ; 2 = CLK_100M_BMC_PE_DN
R7C3  RES  51.1 1.0% CHIP  pkg 0402  page 212 : 1 = PVCCIO_CPU0 ; 2 = GND
